# TIMECARD (Time Appliance Project (Time Card)) — schematic netlist excerpt (pin names and nets, part order shuffled) for the footprints in the layout excerpt that follows; sources: Cadence DE-HDL packaged netlist, KiCad conversion of R4006-B0001-02_R01.brd

R87  RESISTOR  0OHM -  pkg SMC_0402R_H016  page 21 : \1\ = FPGA_IN_MAC_PPS_OUTP ; \2\ = R_MAC_PPS_OUTP
R95  RESISTOR  33OHM 1%  pkg SMC_0402R_H016  page 21 : \1\ = R_MAC_UART_RX_FPGA_TX ; \2\ = UART_MAC_RX_FPGA_TX

(kicad_pcb
	(version 20260206)
	(generator "pcbnew")
	(generator_version "10.0")
	(general
		(thickness 1.6)
		(legacy_teardrops no)
	)
	(paper "A4")
	(title_block
		(title "timecard-production-celestica-r4006 — R4006-B0001-02_R01.brd")
		(comment 1 "Time Appliance Project (Time Card) / footprints 30-32 of 1113")
	)
	(layers
		(0 "F.Cu" signal "TOP")
		(4 "In1.Cu" signal "L02_GND1")
		(6 "In2.Cu" signal "L03_SIG1")
		(8 "In3.Cu" signal "L04_GND2")
		(10 "In4.Cu" signal "L05_VCC1")
		(12 "In5.Cu" signal "L06_VCC2")
		(14 "In6.Cu" signal "L07_GND3")
		(16 "In7.Cu" signal "L08_SIG2")
		(18 "In8.Cu" signal "L09_GND4")
		(2 "B.Cu" signal "BOTTOM")
		(9 "F.Adhes" user "F.Adhesive")
		(11 "B.Adhes" user "B.Adhesive")
		(13 "F.Paste" user "Package Geometry/Pastemask Top")
		(15 "B.Paste" user "Package Geometry/Pastemask Bottom")
		(5 "F.SilkS" user "Ref Des/Silkscreen Top")
		(7 "B.SilkS" user "Ref Des/Silkscreen Bottom")
		(1 "F.Mask" user "Board Geometry/Soldermask Top")
		(3 "B.Mask" user "Board Geometry/Soldermask Bottom")
		(17 "Dwgs.User" user "User.Drawings")
		(19 "Cmts.User" user "User.Comments")
		(21 "Eco1.User" user "User.Eco1")
		(23 "Eco2.User" user "User.Eco2")
		(25 "Edge.Cuts" user "Board Geometry/Outline")
		(27 "Margin" user)
		(31 "F.CrtYd" user "Package Geometry/Place Bound Top")
		(29 "B.CrtYd" user "Package Geometry/Place Bound Bottom")
		(35 "F.Fab" user "Ref Des/Assembly Top")
		(33 "B.Fab" user "Ref Des/Assembly Bottom")
	)
	(footprint ""
		(layer "F.Cu")
		(at 124.587 -51.435 180)
		(property "Reference" "R95"
			(at -0.127 -2.45237 0)
			(unlocked yes)
			(layer "F.SilkS")
			(effects
				(font
					(size 0.7874 0.5842)
					(thickness 0.1524)
				)
			)
		)
		(property "Value" "VAL*"
			(at 0.02032 2.13233 180)
			(unlocked yes)
			(layer "F.Fab")
			(hide yes)
			(effects
				(font
					(size 0.7874 0.5842)
					(thickness 0.1524)
				)
			)
		)
		(property "Tolerance" "TOL*"
			(at 0.044704 3.05435 180)
			(unlocked yes)
			(layer "Cmts.User")
			(hide yes)
			(effects
				(font
					(size 0.7874 0.5842)
					(thickness 0.1524)
				)
			)
		)
		(property "User Part Number" "PARTNUM*"
			(at 0.02032 4.024884 180)
			(unlocked yes)
			(layer "Cmts.User")
			(hide yes)
			(effects
				(font
					(size 0.7874 0.5842)
					(thickness 0.1524)
				)
			)
		)
		(property "Device Type" "RESISTOR-G155-133R0-01,33OHM,1%"
			(at 0.008382 1.210564 180)
			(unlocked yes)
			(layer "F.Fab")
			(hide yes)
			(effects
				(font
					(size 0.7874 0.5842)
					(thickness 0.1524)
				)
			)
		)
		(duplicate_pad_numbers_are_jumpers no)
		(fp_line
			(start 1.143 0.5588)
			(end 1.143 -0.5588)
			(stroke
				(width 0.1)
				(type default)
			)
			(layer "F.SilkS")
		)
		(fp_line
			(start 1.143 -0.5588)
			(end -1.143 -0.5588)
			(stroke
				(width 0.1)
				(type default)
			)
			(layer "F.SilkS")
		)
		(fp_line
			(start -1.143 0.5588)
			(end 1.143 0.5588)
			(stroke
				(width 0.1)
				(type default)
			)
			(layer "F.SilkS")
		)
		(fp_line
			(start -1.143 -0.5588)
			(end -1.143 0.5588)
			(stroke
				(width 0.1)
				(type default)
			)
			(layer "F.SilkS")
		)
		(fp_rect
			(start 1.143 -0.5588)
			(end -1.143 0.5588)
			(stroke
				(width 0)
				(type default)
			)
			(fill no)
			(layer "F.CrtYd")
		)
		(fp_line
			(start 0.508 0.3048)
			(end 0.508 -0.3048)
			(stroke
				(width 0.1)
				(type default)
			)
			(layer "F.Fab")
		)
		(fp_line
			(start 0.508 -0.3048)
			(end -0.508 -0.3048)
			(stroke
				(width 0.1)
				(type default)
			)
			(layer "F.Fab")
		)
		(fp_line
			(start -0.508 0.3048)
			(end 0.508 0.3048)
			(stroke
				(width 0.1)
				(type default)
			)
			(layer "F.Fab")
		)
		(fp_line
			(start -0.508 -0.3048)
			(end -0.508 0.3048)
			(stroke
				(width 0.1)
				(type default)
			)
			(layer "F.Fab")
		)
		(pad "1" smd rect
			(at -0.5334 0 180)
			(size 0.7112 0.6096)
			(layers "F.Cu" "F.Mask" "F.Paste")
			(net "R_MAC_UART_RX_FPGA_TX")
		)
		(pad "2" smd rect
			(at 0.5334 0 180)
			(size 0.7112 0.6096)
			(layers "F.Cu" "F.Mask" "F.Paste")
			(net "UART_MAC_RX_FPGA_TX")
		)
		(zone
			(layer "F.Cu")
			(hatch none 0.5)
			(connect_pads
				(clearance 0)
			)
			(min_thickness 0.25)
			(keepout
				(tracks allowed)
				(vias not_allowed)
				(pads allowed)
				(copperpour not_allowed)
				(footprints allowed)
			)
			(placement
				(enabled no)
				(sheetname "")
			)
			(fill
				(thermal_gap 0.5)
				(thermal_bridge_width 0.5)
				(island_removal_mode 0)
			)
			(polygon
				(pts
					(xy 124.5108 -51.1302) (xy 124.6632 -51.1302) (xy 124.6632 -51.7398) (xy 124.5108 -51.7398)
				)
			)
		)
	)
	(footprint ""
		(layer "F.Cu")
		(at 79.8576 -45.72 180)
		(property "Reference" "R87"
			(at -0.0254 -14.13637 0)
			(unlocked yes)
			(layer "F.SilkS")
			(effects
				(font
					(size 0.7874 0.5842)
					(thickness 0.1524)
				)
			)
		)
		(property "Value" "VAL*"
			(at 0.02032 2.13233 180)
			(unlocked yes)
			(layer "F.Fab")
			(hide yes)
			(effects
				(font
					(size 0.7874 0.5842)
					(thickness 0.1524)
				)
			)
		)
		(property "Device Type" "RESISTOR-G155-100R0-J0,0OHM,-"
			(at 0.008382 1.210564 180)
			(unlocked yes)
			(layer "F.Fab")
			(hide yes)
			(effects
				(font
					(size 0.7874 0.5842)
					(thickness 0.1524)
				)
			)
		)
		(property "User Part Number" "PARTNUM*"
			(at 0.02032 4.024884 180)
			(unlocked yes)
			(layer "Cmts.User")
			(hide yes)
			(effects
				(font
					(size 0.7874 0.5842)
					(thickness 0.1524)
				)
			)
		)
		(property "Tolerance" "TOL*"
			(at 0.044704 3.05435 180)
			(unlocked yes)
			(layer "Cmts.User")
			(hide yes)
			(effects
				(font
					(size 0.7874 0.5842)
					(thickness 0.1524)
				)
			)
		)
		(duplicate_pad_numbers_are_jumpers no)
		(fp_line
			(start 1.143 0.5588)
			(end 1.143 -0.5588)
			(stroke
				(width 0.1)
				(type default)
			)
			(layer "F.SilkS")
		)
		(fp_line
			(start 1.143 -0.5588)
			(end -1.143 -0.5588)
			(stroke
				(width 0.1)
				(type default)
			)
			(layer "F.SilkS")
		)
		(fp_line
			(start -1.143 0.5588)
			(end 1.143 0.5588)
			(stroke
				(width 0.1)
				(type default)
			)
			(layer "F.SilkS")
		)
		(fp_line
			(start -1.143 -0.5588)
			(end -1.143 0.5588)
			(stroke
				(width 0.1)
				(type default)
			)
			(layer "F.SilkS")
		)
		(fp_rect
			(start 1.143 -0.5588)
			(end -1.143 0.5588)
			(stroke
				(width 0)
				(type default)
			)
			(fill no)
			(layer "F.CrtYd")
		)
		(fp_line
			(start 0.508 0.3048)
			(end 0.508 -0.3048)
			(stroke
				(width 0.1)
				(type default)
			)
			(layer "F.Fab")
		)
		(fp_line
			(start 0.508 -0.3048)
			(end -0.508 -0.3048)
			(stroke
				(width 0.1)
				(type default)
			)
			(layer "F.Fab")
		)
		(fp_line
			(start -0.508 0.3048)
			(end 0.508 0.3048)
			(stroke
				(width 0.1)
				(type default)
			)
			(layer "F.Fab")
		)
		(fp_line
			(start -0.508 -0.3048)
			(end -0.508 0.3048)
			(stroke
				(width 0.1)
				(type default)
			)
			(layer "F.Fab")
		)
		(pad "1" smd rect
			(at -0.5334 0 180)
			(size 0.7112 0.6096)
			(layers "F.Cu" "F.Mask" "F.Paste")
			(net "FPGA_IN_MAC_PPS_OUTP")
		)
		(pad "2" smd rect
			(at 0.5334 0 180)
			(size 0.7112 0.6096)
			(layers "F.Cu" "F.Mask" "F.Paste")
			(net "R_MAC_PPS_OUTP")
		)
		(zone
			(layer "F.Cu")
			(hatch none 0.5)
			(connect_pads
				(clearance 0)
			)
			(min_thickness 0.25)
			(keepout
				(tracks allowed)
				(vias not_allowed)
				(pads allowed)
				(copperpour not_allowed)
				(footprints allowed)
			)
			(placement
				(enabled no)
				(sheetname "")
			)
			(fill
				(thermal_gap 0.5)
				(thermal_bridge_width 0.5)
				(island_removal_mode 0)
			)
			(polygon
				(pts
					(xy 79.7814 -45.4152) (xy 79.9338 -45.4152) (xy 79.9338 -46.0248) (xy 79.7814 -46.0248)
				)
			)
		)
	)
	(footprint ""
		(layer "F.Cu")
		(at 55.245 -123.698)
		(property "Reference" "SP79"
			(at 0 0 0)
			(layer "F.SilkS")
			(hide yes)
			(effects
				(font
					(size 1.27 1.27)
				)
			)
		)
		(property "Value" ""
			(at 0 0 0)
			(layer "F.Fab")
			(effects
				(font
					(size 1.27 1.27)
				)
			)
		)
		(duplicate_pad_numbers_are_jumpers no)
	)
)
